(kicad_pcb
	(version 20221018)
	(generator pcbnew)
	(general
    (thickness 1.7403)
  )
	(paper "A4")
	(title_block
    (title "Data Center RDIMM DDR4 Tester")
    (date "2024-09-30")
    (rev "1.2.4")
		(comment 9 "footprints 337-346 of 690")
	)
	(layers
    (0 "F.Cu" signal)
    (1 "In1.Cu" power)
    (2 "In2.Cu" signal)
    (3 "In3.Cu" power)
    (4 "In4.Cu" power)
    (5 "In5.Cu" signal)
    (6 "In6.Cu" power)
    (7 "In7.Cu" signal)
    (8 "In8.Cu" power)
    (9 "In9.Cu" signal)
    (10 "In10.Cu" power)
    (31 "B.Cu" signal)
    (32 "B.Adhes" user "B.Adhesive")
    (33 "F.Adhes" user "F.Adhesive")
    (34 "B.Paste" user)
    (35 "F.Paste" user)
    (36 "B.SilkS" user "B.Silkscreen")
    (37 "F.SilkS" user "F.Silkscreen")
    (38 "B.Mask" user)
    (39 "F.Mask" user)
    (40 "Dwgs.User" user "User.Drawings")
    (41 "Cmts.User" user "User.Comments")
    (42 "Eco1.User" user "User.Eco1")
    (43 "Eco2.User" user "User.Eco2")
    (44 "Edge.Cuts" user)
    (45 "Margin" user)
    (46 "B.CrtYd" user "B.Courtyard")
    (47 "F.CrtYd" user "F.Courtyard")
    (48 "B.Fab" user)
    (49 "F.Fab" user)
  )
	(footprint "data-center-rdimm-ddr4-tester-footprints:C_0201" (layer "F.Cu")
    (at 252.85 80.5 90)
    (descr "Capacitor SMD 0201")
    (tags "capacitor SMD 0201")
    (property "Author" "Antmicro")
    (property "Dielectric" "")
    (property "License" "Apache-2.0")
    (property "MPN" "CC0201KRX6S5BB104")
    (property "Manufacturer" "Yaego")
    (property "Sheetfile" "fmc_hpc.kicad_sch")
    (property "Sheetname" "FMC HPC")
    (property "Val" "100n")
    (property "Voltage" "")
    (property "ki_description" " ")
    (attr smd)
    (fp_text reference "C257" (at -1.31 -0.42 90) (layer "F.SilkS")
        (effects (font (size 0.7 0.7) (thickness 0.15)) (justify left bottom))
    )
    (fp_text value "C_100n_0201" (at 0 1.4 90) (layer "F.Fab") hide
        (effects (font (size 0.7 0.7) (thickness 0.15)) (justify left bottom))
    )
    (fp_text user "${REFERENCE}" (at -0.72 3.4 90) (layer "F.Fab") hide
        (effects (font (size 0.7 0.7) (thickness 0.15)) (justify left bottom))
    )
    (fp_text user "Author: Antmicro" (at -0.72 5.4 90) (layer "F.Fab") hide
        (effects (font (size 0.7 0.7) (thickness 0.15)) (justify left bottom))
    )
    (fp_text user "License: Apache-2.0" (at -0.72 4.4 90) (layer "F.Fab") hide
        (effects (font (size 0.7 0.7) (thickness 0.15)) (justify left bottom))
    )
    (fp_rect (start -0.72 -0.38) (end 0.72 0.38)
      (stroke (width 0.05) (type solid)) (fill none) (layer "F.CrtYd"))
    (fp_rect (start 0.3 0.15) (end -0.301 -0.149)
      (stroke (width 0.15) (type solid)) (fill none) (layer "F.Fab"))
    (pad "" smd roundrect (at -0.349 -0.002 90) (size 0.318 0.36) (layers "F.Paste") (roundrect_rratio 0.25))
    (pad "" smd roundrect (at 0.341 -0.002 90) (size 0.318 0.36) (layers "F.Paste") (roundrect_rratio 0.25))
    (pad "1" smd roundrect (at -0.321 -0.002 90) (size 0.46 0.4) (layers "F.Cu" "F.Mask") (roundrect_rratio 0.25)
      (net 535 "12P0V") (pintype "passive"))
    (pad "2" smd roundrect (at 0.32 -0.002 90) (size 0.46 0.4) (layers "F.Cu" "F.Mask") (roundrect_rratio 0.25)
      (net 9 "GND") (pintype "passive"))
  )
	(footprint "data-center-rdimm-ddr4-tester-footprints:Fiducial_1mm_Mask2mm" (layer "F.Cu")
    (at 114.35 48.55)
    (descr "Circular Fiducial, 1mm bare copper, 3mm soldermask opening")
    (tags "fiducial")
    (property "Author" "Antmicro")
    (property "License" "Apache-2.0")
    (property "MPN" "")
    (property "Manufacturer" "")
    (property "Sheetfile" "data-center-rdimm-ddr4-tester.kicad_sch")
    (property "Sheetname" "")
    (property "exclude_from_bom" "")
    (property "ki_description" "Fiducial Marker for use with single board only")
    (attr exclude_from_pos_files exclude_from_bom)
    (fp_text reference "FID1" (at 1.39 -0.43) (layer "F.SilkS")
        (effects (font (size 0.7 0.7) (thickness 0.15)) (justify left bottom))
    )
    (fp_text value "Fiducial_1mm_Mask2mm" (at 0 2.2) (layer "F.Fab")
        (effects (font (size 0.7 0.7) (thickness 0.15)) (justify left bottom))
    )
    (fp_text user "${REFERENCE}" (at -1.25 4.603) (layer "F.Fab") hide
        (effects (font (size 0.7 0.7) (thickness 0.15)) (justify left bottom))
    )
    (fp_text user "Author: Antmicro" (at -1.25 5.803) (layer "F.Fab") hide
        (effects (font (size 0.7 0.7) (thickness 0.15)) (justify left bottom))
    )
    (fp_text user "License: Apache-2.0" (at -1.25 7.003) (layer "F.Fab") hide
        (effects (font (size 0.7 0.7) (thickness 0.15)) (justify left bottom))
    )
    (fp_circle (center 0 0) (end 1.24 0)
      (stroke (width 0.05) (type solid)) (fill none) (layer "F.CrtYd"))
    (fp_circle (center 0 0) (end 0.999 0)
      (stroke (width 0.15) (type solid)) (fill none) (layer "F.Fab"))
    (pad "" smd circle (at 0 0) (size 1 1) (layers "F.Cu" "F.Mask")
      (solder_mask_margin 0.5) (clearance 0.5))
  )
	(footprint "data-center-rdimm-ddr4-tester-footprints:NetTie-2_SMD_Pad0.127mm" (layer "F.Cu")
    (at 123.2 87.53 90)
    (descr "Net tie, 2 pin, 0.127mm  SMD pads")
    (tags "net tie")
    (property "Author" "Antmicro")
    (property "License" "Apache-2.0")
    (property "MPN" "")
    (property "Manufacturer" "")
    (property "Sheetfile" "supply.kicad_sch")
    (property "Sheetname" "Supply")
    (property "ki_description" "Net tie, 2 pins")
    (property "ki_keywords" "net tie short")
    (attr through_hole exclude_from_pos_files)
    (net_tie_pad_groups "1, 2")
    (fp_text reference "NT5" (at -0.128 -1.345 90) (layer "F.SilkS") hide
        (effects (font (size 0.7 0.7) (thickness 0.15)) (justify left bottom))
    )
    (fp_text value "Net-Tie_2" (at 0 1.199 90) (layer "F.Fab") hide
        (effects (font (size 0.7 0.7) (thickness 0.15)) (justify left bottom))
    )
    (fp_text user "Author: Antmicro" (at -0.128 4.4 90) (layer "F.Fab") hide
        (effects (font (size 0.7 0.7) (thickness 0.15)) (justify left bottom))
    )
    (fp_text user "${REFERENCE}" (at -0.128 3.2 90) (layer "F.Fab") hide
        (effects (font (size 0.7 0.7) (thickness 0.15)) (justify left bottom))
    )
    (fp_text user "License: Apache-2.0" (at -0.128 5.6 90) (layer "F.Fab") hide
        (effects (font (size 0.7 0.7) (thickness 0.15)) (justify left bottom))
    )
    (fp_poly
      (pts
        (xy -0.0635 -0.0635)
        (xy 0.0625 -0.0635)
        (xy 0.0625 0.0635)
        (xy -0.0635 0.0635)
      )

      (stroke (width 0) (type solid)) (fill solid) (layer "F.Cu"))
    (pad "1" smd roundrect (at -0.127 0 270) (size 0.127 0.127) (layers "F.Cu") (roundrect_rratio 0.5)
      (chamfer_ratio 0) (chamfer top_left bottom_left)
      (net 836 "/Supply/VPP_SEN_-") (pinfunction "1") (pintype "passive"))
    (pad "2" smd roundrect (at 0.126 0 90) (size 0.127 0.127) (layers "F.Cu") (roundrect_rratio 0.5)
      (chamfer_ratio 0) (chamfer top_left bottom_left)
      (net 184 "VPP") (pinfunction "2") (pintype "passive"))
  )
	(footprint "data-center-rdimm-ddr4-tester-footprints:NetTie-2_SMD_Pad0.127mm" (layer "F.Cu")
    (at 112.425 90.67 90)
    (descr "Net tie, 2 pin, 0.127mm  SMD pads")
    (tags "net tie")
    (property "Author" "Antmicro")
    (property "License" "Apache-2.0")
    (property "MPN" "")
    (property "Manufacturer" "")
    (property "Sheetfile" "supply.kicad_sch")
    (property "Sheetname" "Supply")
    (property "ki_description" "Net tie, 2 pins")
    (property "ki_keywords" "net tie short")
    (attr through_hole exclude_from_pos_files)
    (net_tie_pad_groups "1, 2")
    (fp_text reference "NT6" (at -0.128 -1.345 90) (layer "F.SilkS") hide
        (effects (font (size 0.7 0.7) (thickness 0.15)) (justify left bottom))
    )
    (fp_text value "Net-Tie_2" (at 0 1.199 90) (layer "F.Fab") hide
        (effects (font (size 0.7 0.7) (thickness 0.15)) (justify left bottom))
    )
    (fp_text user "${REFERENCE}" (at -0.128 3.2 90) (layer "F.Fab") hide
        (effects (font (size 0.7 0.7) (thickness 0.15)) (justify left bottom))
    )
    (fp_text user "Author: Antmicro" (at -0.128 4.4 90) (layer "F.Fab") hide
        (effects (font (size 0.7 0.7) (thickness 0.15)) (justify left bottom))
    )
    (fp_text user "License: Apache-2.0" (at -0.128 5.6 90) (layer "F.Fab") hide
        (effects (font (size 0.7 0.7) (thickness 0.15)) (justify left bottom))
    )
    (fp_poly
      (pts
        (xy -0.0635 -0.0635)
        (xy 0.0625 -0.0635)
        (xy 0.0625 0.0635)
        (xy -0.0635 0.0635)
      )

      (stroke (width 0) (type solid)) (fill solid) (layer "F.Cu"))
    (pad "1" smd roundrect (at -0.127 0 270) (size 0.127 0.127) (layers "F.Cu") (roundrect_rratio 0.5)
      (chamfer_ratio 0) (chamfer top_left bottom_left)
      (net 837 "/Supply/VTT_SEN_-") (pinfunction "1") (pintype "passive"))
    (pad "2" smd roundrect (at 0.126 0 90) (size 0.127 0.127) (layers "F.Cu") (roundrect_rratio 0.5)
      (chamfer_ratio 0) (chamfer top_left bottom_left)
      (net 186 "VTT") (pinfunction "2") (pintype "passive"))
  )
	(footprint "data-center-rdimm-ddr4-tester-footprints:R_1206_3216Metric" (layer "F.Cu")
    (at 123.2 88.4 90)
    (property "Author" "Antmicro")
    (property "License" "Apache-2.0")
    (property "MPN" "RL1206FR-7W0R01L")
    (property "Manufacturer" "Yaego")
    (property "Sheetfile" "supply.kicad_sch")
    (property "Sheetname" "Supply")
    (property "Tolerance" "1%")
    (property "Val" "0R01")
    (property "ki_description" "0R01 resistor in 1206 package with unspecified tolerance")
    (attr smd)
    (fp_text reference "R198" (at 0 -1.2 90) (layer "F.SilkS")
        (effects (font (size 0.7 0.7) (thickness 0.15)) (justify left bottom))
    )
    (fp_text value "R_0R01_1206" (at 0 2 90) (layer "F.Fab") hide
        (effects (font (size 0.7 0.7) (thickness 0.15)) (justify left bottom))
    )
    (fp_text user "License: Apache-2.0" (at -2.401 6.3 90) (layer "F.Fab") hide
        (effects (font (size 0.7 0.7) (thickness 0.15)) (justify left bottom))
    )
    (fp_text user "${REFERENCE}" (at -2.401 3.5 90) (layer "F.Fab") hide
        (effects (font (size 0.7 0.7) (thickness 0.15)) (justify left bottom))
    )
    (fp_text user "Author: Antmicro" (at -2.401 4.899 90) (layer "F.Fab") hide
        (effects (font (size 0.7 0.7) (thickness 0.15)) (justify left bottom))
    )
    (fp_line (start 0 -0.902) (end -0.5 -0.902)
      (stroke (width 0.15) (type solid)) (layer "F.SilkS"))
    (fp_line (start 0 -0.902) (end 0.498 -0.902)
      (stroke (width 0.15) (type solid)) (layer "F.SilkS"))
    (fp_line (start 0 0.9) (end -0.5 0.9)
      (stroke (width 0.15) (type solid)) (layer "F.SilkS"))
    (fp_line (start 0 0.9) (end 0.498 0.9)
      (stroke (width 0.15) (type solid)) (layer "F.SilkS"))
    (fp_rect (start -2.25 -1.05) (end 2.25 1.05)
      (stroke (width 0.05) (type solid)) (fill none) (layer "F.CrtYd"))
    (fp_line (start -1.601 -0.802) (end -1.601 0.8)
      (stroke (width 0.15) (type solid)) (layer "F.Fab"))
    (fp_line (start -1.601 -0.802) (end 1.6 -0.802)
      (stroke (width 0.15) (type solid)) (layer "F.Fab"))
    (fp_line (start -1.601 0.8) (end 1.6 0.8)
      (stroke (width 0.15) (type solid)) (layer "F.Fab"))
    (fp_line (start 1.6 -0.802) (end 1.6 0.8)
      (stroke (width 0.15) (type solid)) (layer "F.Fab"))
    (pad "1" smd roundrect (at -1.5 0 90) (size 1.2 1.8) (layers "F.Cu" "F.Paste" "F.Mask") (roundrect_rratio 0.15)
      (net 303 "VCC2V5") (pintype "passive"))
    (pad "2" smd roundrect (at 1.499 0 90) (size 1.2 1.8) (layers "F.Cu" "F.Paste" "F.Mask") (roundrect_rratio 0.15)
      (net 184 "VPP") (pintype "passive"))
  )
	(footprint "data-center-rdimm-ddr4-tester-footprints:R_0201" (layer "F.Cu")
    (at 164.04 109.02 90)
    (descr "Resistor SMD 0201")
    (tags "resistor SMD 0201")
    (property "Author" "Antmicro")
    (property "License" "Apache-2.0")
    (property "MPN" "CR0201-FX-0R00GLF")
    (property "Manufacturer" "Bourns")
    (property "Sheetfile" "ethernet.kicad_sch")
    (property "Sheetname" "Ethernet")
    (property "Tolerance" "1%")
    (property "Val" "0R")
    (property "ki_description" "0R resistor in 0201 package with 1% tolerance")
    (attr smd)
    (fp_text reference "R112" (at -3.43 0.48 90) (layer "F.SilkS")
        (effects (font (size 0.7 0.7) (thickness 0.15)) (justify left bottom))
    )
    (fp_text value "R_0R_0201" (at 0 1.25 90) (layer "F.Fab") hide
        (effects (font (size 0.7 0.7) (thickness 0.15)) (justify left bottom))
    )
    (fp_text user "${REFERENCE}" (at -0.71 3.25 90) (layer "F.Fab") hide
        (effects (font (size 0.7 0.7) (thickness 0.15)) (justify left bottom))
    )
    (fp_text user "Author: Antmicro" (at -0.71 5.25 90) (layer "F.Fab") hide
        (effects (font (size 0.7 0.7) (thickness 0.15)) (justify left bottom))
    )
    (fp_text user "License: Apache-2.0" (at -0.71 4.25 90) (layer "F.Fab") hide
        (effects (font (size 0.7 0.7) (thickness 0.15)) (justify left bottom))
    )
    (fp_rect (start -0.71 -0.36) (end 0.71 0.36)
      (stroke (width 0.05) (type solid)) (fill none) (layer "F.CrtYd"))
    (fp_rect (start -0.3 -0.15) (end 0.298 0.148)
      (stroke (width 0.15) (type solid)) (fill none) (layer "F.Fab"))
    (pad "" smd roundrect (at -0.346 0 90) (size 0.318 0.36) (layers "F.Paste") (roundrect_rratio 0.25))
    (pad "" smd roundrect (at 0.344 0 90) (size 0.318 0.36) (layers "F.Paste") (roundrect_rratio 0.25))
    (pad "1" smd roundrect (at -0.32 0 90) (size 0.46 0.4) (layers "F.Cu" "F.Mask") (roundrect_rratio 0.25)
      (net 547 "/Ethernet/INT_ETH4_N") (pintype "passive"))
    (pad "2" smd roundrect (at 0.32 0 90) (size 0.46 0.4) (layers "F.Cu" "F.Mask") (roundrect_rratio 0.25)
      (net 831 "/Ethernet/ETH4_BP_N") (pintype "passive"))
  )
	(footprint "data-center-rdimm-ddr4-tester-footprints:R_1206_3216Metric" (layer "F.Cu")
    (at 152.3 121.7)
    (property "Author" "Antmicro")
    (property "License" "Apache-2.0")
    (property "MPN" "RL1206FR-7W0R01L")
    (property "Manufacturer" "Yaego")
    (property "Sheetfile" "supply.kicad_sch")
    (property "Sheetname" "Supply")
    (property "Tolerance" "1%")
    (property "Val" "0R01")
    (property "ki_description" "0R01 resistor in 1206 package with unspecified tolerance")
    (attr smd)
    (fp_text reference "R162" (at -1.45 1.86) (layer "F.SilkS")
        (effects (font (size 0.7 0.7) (thickness 0.15)) (justify left bottom))
    )
    (fp_text value "R_0R01_1206" (at 0 2) (layer "F.Fab") hide
        (effects (font (size 0.7 0.7) (thickness 0.15)) (justify left bottom))
    )
    (fp_text user "License: Apache-2.0" (at -2.401 6.3) (layer "F.Fab") hide
        (effects (font (size 0.7 0.7) (thickness 0.15)) (justify left bottom))
    )
    (fp_text user "${REFERENCE}" (at -2.401 3.5) (layer "F.Fab") hide
        (effects (font (size 0.7 0.7) (thickness 0.15)) (justify left bottom))
    )
    (fp_text user "Author: Antmicro" (at -2.401 4.899) (layer "F.Fab") hide
        (effects (font (size 0.7 0.7) (thickness 0.15)) (justify left bottom))
    )
    (fp_line (start 0 -0.902) (end -0.5 -0.902)
      (stroke (width 0.15) (type solid)) (layer "F.SilkS"))
    (fp_line (start 0 -0.902) (end 0.498 -0.902)
      (stroke (width 0.15) (type solid)) (layer "F.SilkS"))
    (fp_line (start 0 0.9) (end -0.5 0.9)
      (stroke (width 0.15) (type solid)) (layer "F.SilkS"))
    (fp_line (start 0 0.9) (end 0.498 0.9)
      (stroke (width 0.15) (type solid)) (layer "F.SilkS"))
    (fp_rect (start -2.25 -1.05) (end 2.25 1.05)
      (stroke (width 0.05) (type solid)) (fill none) (layer "F.CrtYd"))
    (fp_line (start -1.601 -0.802) (end -1.601 0.8)
      (stroke (width 0.15) (type solid)) (layer "F.Fab"))
    (fp_line (start -1.601 -0.802) (end 1.6 -0.802)
      (stroke (width 0.15) (type solid)) (layer "F.Fab"))
    (fp_line (start -1.601 0.8) (end 1.6 0.8)
      (stroke (width 0.15) (type solid)) (layer "F.Fab"))
    (fp_line (start 1.6 -0.802) (end 1.6 0.8)
      (stroke (width 0.15) (type solid)) (layer "F.Fab"))
    (pad "1" smd roundrect (at -1.5 0) (size 1.2 1.8) (layers "F.Cu" "F.Paste" "F.Mask") (roundrect_rratio 0.15)
      (net 176 "VCC1V2") (pintype "passive"))
    (pad "2" smd roundrect (at 1.499 0) (size 1.2 1.8) (layers "F.Cu" "F.Paste" "F.Mask") (roundrect_rratio 0.15)
      (net 306 "1V2_SYS") (pintype "passive"))
  )
	(footprint "data-center-rdimm-ddr4-tester-footprints:R_0402_1005Metric" (layer "F.Cu")
    (at 238.785 123.3 180)
    (descr "Resistor SMD 0402")
    (tags "resistor SMD 0402")
    (property "Author" "Antmicro")
    (property "License" "Apache-2.0")
    (property "MPN" "CR0402-FX-4702GLF")
    (property "Manufacturer" "Bourns")
    (property "Sheetfile" "supply.kicad_sch")
    (property "Sheetname" "Supply")
    (property "Tolerance" "1%")
    (property "Val" "47k")
    (property "ki_description" "47k resistor in 0402 package with 1% tolerance")
    (attr smd)
    (fp_text reference "R120" (at -0.785 -0.11 180) (layer "F.SilkS")
        (effects (font (size 0.7 0.7) (thickness 0.15)) (justify left bottom))
    )
    (fp_text value "R_47k_0402" (at 0 1.4 180) (layer "F.Fab") hide
        (effects (font (size 0.7 0.7) (thickness 0.15)) (justify left bottom))
    )
    (fp_text user "${REFERENCE}" (at -0.95 3.168 180) (layer "F.Fab") hide
        (effects (font (size 0.7 0.7) (thickness 0.15)) (justify left bottom))
    )
    (fp_text user "Author: Antmicro" (at -0.95 4.169 180) (layer "F.Fab") hide
        (effects (font (size 0.7 0.7) (thickness 0.15)) (justify left bottom))
    )
    (fp_text user "License: Apache-2.0" (at -0.95 5.169 180) (layer "F.Fab") hide
        (effects (font (size 0.7 0.7) (thickness 0.15)) (justify left bottom))
    )
    (fp_rect (start -0.93 -0.47) (end 0.93 0.47)
      (stroke (width 0.05) (type solid)) (fill none) (layer "F.CrtYd"))
    (fp_rect (start -0.5 -0.25) (end 0.5 0.25)
      (stroke (width 0.15) (type solid)) (fill none) (layer "F.Fab"))
    (pad "1" smd roundrect (at -0.485 0 180) (size 0.59 0.64) (layers "F.Cu" "F.Paste" "F.Mask") (roundrect_rratio 0.25)
      (net 9 "GND") (pintype "passive"))
    (pad "2" smd roundrect (at 0.485 0 180) (size 0.59 0.64) (layers "F.Cu" "F.Paste" "F.Mask") (roundrect_rratio 0.25)
      (net 108 "Net-(U27-~{OE})") (pintype "passive"))
  )
	(footprint "data-center-rdimm-ddr4-tester-footprints:C_0402_1005Metric" (layer "F.Cu")
    (at 256.63 100.5)
    (descr "Capacitor SMD 0402")
    (tags "capacitor SMD 0402")
    (property "Author" "Antmicro")
    (property "Dielectric" "X5R")
    (property "License" "Apache-2.0")
    (property "MPN" "GRM155R61H104KE14D")
    (property "Manufacturer" "Murata")
    (property "Sheetfile" "pcie.kicad_sch")
    (property "Sheetname" "FPGA banks 115-116")
    (property "Val" "100n")
    (property "Voltage" "50V")
    (property "ki_description" " ")
    (attr smd)
    (fp_text reference "C194" (at -0.65 2.28) (layer "F.SilkS")
        (effects (font (size 0.7 0.7) (thickness 0.15)) (justify left bottom))
    )
    (fp_text value "C_100n_0402" (at 0 1.4) (layer "F.Fab") hide
        (effects (font (size 0.7 0.7) (thickness 0.15)) (justify left bottom))
    )
    (fp_text user "License: Apache-2.0" (at -0.932 5.17) (layer "F.Fab") hide
        (effects (font (size 0.7 0.7) (thickness 0.15)) (justify left bottom))
    )
    (fp_text user "Author: Antmicro" (at -0.932 4.17) (layer "F.Fab") hide
        (effects (font (size 0.7 0.7) (thickness 0.15)) (justify left bottom))
    )
    (fp_text user "${REFERENCE}" (at -0.932 3.168) (layer "F.Fab") hide
        (effects (font (size 0.7 0.7) (thickness 0.15)) (justify left bottom))
    )
    (fp_rect (start -0.94 -0.47) (end 0.94 0.47)
      (stroke (width 0.05) (type solid)) (fill none) (layer "F.CrtYd"))
    (fp_rect (start -0.499 -0.249) (end 0.499 0.249)
      (stroke (width 0.15) (type solid)) (fill none) (layer "F.Fab"))
    (pad "1" smd roundrect (at -0.484 0) (size 0.59 0.64) (layers "F.Cu" "F.Paste" "F.Mask") (roundrect_rratio 0.25)
      (net 891 "GTR_REFCLK1_C_P") (pintype "passive"))
    (pad "2" smd roundrect (at 0.484 0) (size 0.59 0.64) (layers "F.Cu" "F.Paste" "F.Mask") (roundrect_rratio 0.25)
      (net 883 "/FPGA banks 115-116/GTR_REFCLK1_P") (pintype "passive"))
  )
	(footprint "data-center-rdimm-ddr4-tester-footprints:Testpoint_smd_1mm" (layer "F.Cu")
    (at 143.375 126.65)
    (property "Author" "Antmicro")
    (property "License" "Apache-2.0")
    (property "MPN" "")
    (property "Manufacturer" "")
    (property "Sheetfile" "interfaces.kicad_sch")
    (property "Sheetname" "Interfaces")
    (property "ki_description" "Test Point 1mm")
    (attr exclude_from_pos_files)
    (fp_text reference "VBUS1" (at -3.885 0.4) (layer "F.SilkS")
        (effects (font (size 0.7 0.7) (thickness 0.15)) (justify left bottom))
    )
    (fp_text value "TP_1mm_SMD" (at 0 1.4) (layer "F.Fab") hide
        (effects (font (size 0.7 0.7) (thickness 0.15)) (justify left bottom))
    )
    (fp_text user "License: Apache-2.0" (at -0.5 5.2) (layer "F.Fab") hide
        (effects (font (size 0.7 0.7) (thickness 0.15)) (justify left bottom))
    )
    (fp_text user "Author: Antmicro" (at -0.5 4) (layer "F.Fab") hide
        (effects (font (size 0.7 0.7) (thickness 0.15)) (justify left bottom))
    )
    (fp_text user "${REFERENCE}" (at -0.5 2.8) (layer "F.Fab") hide
        (effects (font (size 0.7 0.7) (thickness 0.15)) (justify left bottom))
    )
    (pad "1" smd circle (at 0 0) (size 1 1) (layers "F.Cu" "F.Mask")
      (net 853 "VBUS") (pinfunction "1") (pintype "passive"))
  )
)
